(kicad_pcb
	(version 20260206)
	(generator "pcbnew")
	(generator_version "10.0")
	(general
		(thickness 1.6)
		(legacy_teardrops no)
	)
	(paper "A4")
	(title_block
		(title "Wiwynn_Tioga_Pass_MB.brd")
		(comment 1 "Tioga Pass / footprints 3659-3666 of 4770")
	)
	(layers
		(0 "F.Cu" signal "TOP")
		(4 "In1.Cu" signal "L2GND")
		(6 "In2.Cu" signal "L3")
		(8 "In3.Cu" signal "L4GND")
		(10 "In4.Cu" signal "L5")
		(12 "In5.Cu" signal "L6GND")
		(14 "In6.Cu" signal "L7VCC")
		(16 "In7.Cu" signal "L8VCC")
		(18 "In8.Cu" signal "L9GND")
		(20 "In9.Cu" signal "L10")
		(22 "In10.Cu" signal "L11GND")
		(24 "In11.Cu" signal "L12")
		(26 "In12.Cu" signal "L13GND")
		(2 "B.Cu" signal "BOTTOM")
		(9 "F.Adhes" user "F.Adhesive")
		(11 "B.Adhes" user "B.Adhesive")
		(13 "F.Paste" user "Package Geometry/Pastemask Top")
		(15 "B.Paste" user "Package Geometry/Pastemask Bottom")
		(5 "F.SilkS" user "Ref Des/Silkscreen Top")
		(7 "B.SilkS" user "Ref Des/Silkscreen Bottom")
		(1 "F.Mask" user "Board Geometry/Soldermask Top")
		(3 "B.Mask" user "Board Geometry/Soldermask Bottom")
		(17 "Dwgs.User" user "User.Drawings")
		(19 "Cmts.User" user "User.Comments")
		(21 "Eco1.User" user "User.Eco1")
		(23 "Eco2.User" user "User.Eco2")
		(25 "Edge.Cuts" user "Board Geometry/Outline")
		(27 "Margin" user)
		(31 "F.CrtYd" user "Package Geometry/Place Bound Top")
		(29 "B.CrtYd" user "Package Geometry/Place Bound Bottom")
		(35 "F.Fab" user "Ref Des/Assembly Top")
		(33 "B.Fab" user "Ref Des/Assembly Bottom")
	)
	(footprint ""
		(layer "B.Cu")
		(at 281.3812 -75.7174 90)
		(property "Reference" "R4P6"
			(at 0 0 90)
			(layer "B.SilkS")
			(hide yes)
			(effects
				(font
					(size 1.27 1.27)
				)
				(justify mirror)
			)
		)
		(property "Value" ""
			(at 0 0 90)
			(layer "B.Fab")
			(effects
				(font
					(size 1.27 1.27)
				)
				(justify mirror)
			)
		)
		(duplicate_pad_numbers_are_jumpers no)
		(fp_rect
			(start -0.2794 -0.1016)
			(end 0.2794 0.9906)
			(stroke
				(width 0)
				(type default)
			)
			(fill no)
			(layer "B.CrtYd")
		)
		(fp_line
			(start 0.2794 -0.1016)
			(end 0.2794 0.9906)
			(stroke
				(width 0.1)
				(type default)
			)
			(layer "B.Fab")
		)
		(fp_line
			(start -0.2794 -0.1016)
			(end 0.2794 -0.1016)
			(stroke
				(width 0.1)
				(type default)
			)
			(layer "B.Fab")
		)
		(fp_line
			(start 0.2794 0.9906)
			(end -0.2794 0.9906)
			(stroke
				(width 0.1)
				(type default)
			)
			(layer "B.Fab")
		)
		(fp_line
			(start -0.2794 0.9906)
			(end -0.2794 -0.1016)
			(stroke
				(width 0.1)
				(type default)
			)
			(layer "B.Fab")
		)
		(pad "1" smd rect
			(at 0 0 270)
			(size 0.508 0.508)
			(layers "B.Cu" "B.Mask" "B.Paste")
			(net "GND")
		)
		(pad "2" smd rect
			(at 0 0.889 270)
			(size 0.508 0.508)
			(layers "B.Cu" "B.Mask" "B.Paste")
			(net "PD_CPU0_DMIMODE_OVERRIDE")
		)
		(zone
			(layer "B.Cu")
			(hatch none 0.5)
			(connect_pads
				(clearance 0)
			)
			(min_thickness 0.25)
			(keepout
				(tracks not_allowed)
				(vias allowed)
				(pads allowed)
				(copperpour not_allowed)
				(footprints allowed)
			)
			(placement
				(enabled no)
				(sheetname "")
			)
			(fill
				(thermal_gap 0.5)
				(thermal_bridge_width 0.5)
				(island_removal_mode 0)
			)
			(polygon
				(pts
					(xy 281.6352 -75.4634) (xy 282.0162 -75.4634) (xy 282.0162 -75.9714) (xy 281.6352 -75.9714)
				)
			)
		)
		(zone
			(layer "B.Cu")
			(hatch none 0.5)
			(connect_pads
				(clearance 0)
			)
			(min_thickness 0.25)
			(keepout
				(tracks allowed)
				(vias not_allowed)
				(pads allowed)
				(copperpour not_allowed)
				(footprints allowed)
			)
			(placement
				(enabled no)
				(sheetname "")
			)
			(fill
				(thermal_gap 0.5)
				(thermal_bridge_width 0.5)
				(island_removal_mode 0)
			)
			(polygon
				(pts
					(xy 281.6352 -75.4634) (xy 282.0162 -75.4634) (xy 282.0162 -75.9714) (xy 281.6352 -75.9714)
				)
			)
		)
	)
	(footprint ""
		(layer "B.Cu")
		(at 253.392432 -3.3528 90)
		(property "Reference" "C5G53"
			(at -1.14681 0.76708 180)
			(unlocked yes)
			(layer "B.SilkS")
			(effects
				(font
					(size 0.7874 0.5842)
					(thickness 0.1524)
				)
				(justify mirror)
			)
		)
		(property "Value" ""
			(at 0 0 90)
			(layer "B.Fab")
			(effects
				(font
					(size 1.27 1.27)
				)
				(justify mirror)
			)
		)
		(duplicate_pad_numbers_are_jumpers no)
		(fp_rect
			(start -0.4953 -0.2032)
			(end 0.4953 1.6002)
			(stroke
				(width 0)
				(type default)
			)
			(fill no)
			(layer "B.CrtYd")
		)
		(fp_line
			(start 0.4953 -0.2032)
			(end -0.4953 -0.2032)
			(stroke
				(width 0.1)
				(type default)
			)
			(layer "B.Fab")
		)
		(fp_line
			(start -0.4953 -0.2032)
			(end -0.4953 1.6002)
			(stroke
				(width 0.1)
				(type default)
			)
			(layer "B.Fab")
		)
		(fp_line
			(start 0.4953 1.6002)
			(end 0.4953 -0.2032)
			(stroke
				(width 0.1)
				(type default)
			)
			(layer "B.Fab")
		)
		(fp_line
			(start -0.4953 1.6002)
			(end 0.4953 1.6002)
			(stroke
				(width 0.1)
				(type default)
			)
			(layer "B.Fab")
		)
		(pad "1" smd rect
			(at 0 0 270)
			(size 0.762 0.889)
			(layers "B.Cu" "B.Mask" "B.Paste")
			(net "PVDDQ_ABC")
		)
		(pad "2" smd rect
			(at 0 1.397 270)
			(size 0.762 0.889)
			(layers "B.Cu" "B.Mask" "B.Paste")
			(net "GND")
		)
		(zone
			(layer "B.Cu")
			(hatch none 0.5)
			(connect_pads
				(clearance 0)
			)
			(min_thickness 0.25)
			(keepout
				(tracks not_allowed)
				(vias allowed)
				(pads allowed)
				(copperpour not_allowed)
				(footprints allowed)
			)
			(placement
				(enabled no)
				(sheetname "")
			)
			(fill
				(thermal_gap 0.5)
				(thermal_bridge_width 0.5)
				(island_removal_mode 0)
			)
			(polygon
				(pts
					(xy 253.836932 -2.9718) (xy 254.344932 -2.9718) (xy 254.344932 -3.7338) (xy 253.836932 -3.7338)
				)
			)
		)
	)
	(footprint ""
		(layer "B.Cu")
		(at 483.017322 -17.929606 -90)
		(property "Reference" "C9G3"
			(at 0 0 90)
			(layer "B.SilkS")
			(hide yes)
			(effects
				(font
					(size 1.27 1.27)
				)
				(justify mirror)
			)
		)
		(property "Value" ""
			(at 0 0 90)
			(layer "B.Fab")
			(effects
				(font
					(size 1.27 1.27)
				)
				(justify mirror)
			)
		)
		(duplicate_pad_numbers_are_jumpers no)
		(fp_poly
			(pts
				(xy -0.3048 -0.1016) (xy -0.3048 0.9906) (xy 0.3048 0.9906) (xy 0.3048 -0.1016)
			)
			(stroke
				(width 0)
				(type default)
			)
			(fill no)
			(layer "B.CrtYd")
		)
		(fp_line
			(start -0.3048 0.9906)
			(end -0.3048 -0.1016)
			(stroke
				(width 0.1)
				(type default)
			)
			(layer "B.Fab")
		)
		(fp_line
			(start 0.3048 0.9906)
			(end -0.3048 0.9906)
			(stroke
				(width 0.1)
				(type default)
			)
			(layer "B.Fab")
		)
		(fp_line
			(start -0.3048 -0.1016)
			(end 0.3048 -0.1016)
			(stroke
				(width 0.1)
				(type default)
			)
			(layer "B.Fab")
		)
		(fp_line
			(start 0.3048 -0.1016)
			(end 0.3048 0.9906)
			(stroke
				(width 0.1)
				(type default)
			)
			(layer "B.Fab")
		)
		(pad "1" smd rect
			(at 0 0 90)
			(size 0.508 0.508)
			(layers "B.Cu" "B.Mask" "B.Paste")
			(net "LED_LAN_0_N")
		)
		(pad "2" smd rect
			(at 0 0.889 90)
			(size 0.508 0.508)
			(layers "B.Cu" "B.Mask" "B.Paste")
			(net "GND")
		)
		(zone
			(layer "B.Cu")
			(hatch none 0.5)
			(connect_pads
				(clearance 0)
			)
			(min_thickness 0.25)
			(keepout
				(tracks not_allowed)
				(vias allowed)
				(pads allowed)
				(copperpour not_allowed)
				(footprints allowed)
			)
			(placement
				(enabled no)
				(sheetname "")
			)
			(fill
				(thermal_gap 0.5)
				(thermal_bridge_width 0.5)
				(island_removal_mode 0)
			)
			(polygon
				(pts
					(xy 482.382322 -17.675606) (xy 482.382322 -18.183606) (xy 482.763322 -18.183606) (xy 482.763322 -17.675606)
				)
			)
		)
		(zone
			(layer "B.Cu")
			(hatch none 0.5)
			(connect_pads
				(clearance 0)
			)
			(min_thickness 0.25)
			(keepout
				(tracks allowed)
				(vias not_allowed)
				(pads allowed)
				(copperpour not_allowed)
				(footprints allowed)
			)
			(placement
				(enabled no)
				(sheetname "")
			)
			(fill
				(thermal_gap 0.5)
				(thermal_bridge_width 0.5)
				(island_removal_mode 0)
			)
			(polygon
				(pts
					(xy 482.763322 -17.675606) (xy 482.763322 -18.183606) (xy 482.382322 -18.183606) (xy 482.382322 -17.675606)
				)
			)
		)
	)
	(footprint ""
		(layer "B.Cu")
		(at 350.2914 -145.923 180)
		(property "Reference" "CT48"
			(at 0.8382 -0.84963 180)
			(unlocked yes)
			(layer "B.SilkS")
			(effects
				(font
					(size 0.7874 0.5842)
					(thickness 0.1524)
				)
				(justify left mirror)
			)
		)
		(property "Value" ""
			(at 0 0 0)
			(layer "B.Fab")
			(effects
				(font
					(size 1.27 1.27)
				)
				(justify mirror)
			)
		)
		(duplicate_pad_numbers_are_jumpers no)
		(fp_poly
			(pts
				(xy -0.3048 -0.1016) (xy -0.3048 0.9906) (xy 0.3048 0.9906) (xy 0.3048 -0.1016)
			)
			(stroke
				(width 0)
				(type default)
			)
			(fill no)
			(layer "B.CrtYd")
		)
		(fp_line
			(start 0.3048 0.9906)
			(end -0.3048 0.9906)
			(stroke
				(width 0.1)
				(type default)
			)
			(layer "B.Fab")
		)
		(fp_line
			(start 0.3048 -0.1016)
			(end 0.3048 0.9906)
			(stroke
				(width 0.1)
				(type default)
			)
			(layer "B.Fab")
		)
		(fp_line
			(start -0.3048 0.9906)
			(end -0.3048 -0.1016)
			(stroke
				(width 0.1)
				(type default)
			)
			(layer "B.Fab")
		)
		(fp_line
			(start -0.3048 -0.1016)
			(end 0.3048 -0.1016)
			(stroke
				(width 0.1)
				(type default)
			)
			(layer "B.Fab")
		)
		(pad "1" smd rect
			(at 0 0)
			(size 0.508 0.508)
			(layers "B.Cu" "B.Mask" "B.Paste")
			(net "A_TSENSE_PVDDQ_DEF")
		)
		(pad "2" smd rect
			(at 0 0.889)
			(size 0.508 0.508)
			(layers "B.Cu" "B.Mask" "B.Paste")
			(net "GND")
		)
		(zone
			(layer "B.Cu")
			(hatch none 0.5)
			(connect_pads
				(clearance 0)
			)
			(min_thickness 0.25)
			(keepout
				(tracks not_allowed)
				(vias allowed)
				(pads allowed)
				(copperpour not_allowed)
				(footprints allowed)
			)
			(placement
				(enabled no)
				(sheetname "")
			)
			(fill
				(thermal_gap 0.5)
				(thermal_bridge_width 0.5)
				(island_removal_mode 0)
			)
			(polygon
				(pts
					(xy 350.0374 -146.558) (xy 350.5454 -146.558) (xy 350.5454 -146.177) (xy 350.0374 -146.177)
				)
			)
		)
		(zone
			(layer "B.Cu")
			(hatch none 0.5)
			(connect_pads
				(clearance 0)
			)
			(min_thickness 0.25)
			(keepout
				(tracks allowed)
				(vias not_allowed)
				(pads allowed)
				(copperpour not_allowed)
				(footprints allowed)
			)
			(placement
				(enabled no)
				(sheetname "")
			)
			(fill
				(thermal_gap 0.5)
				(thermal_bridge_width 0.5)
				(island_removal_mode 0)
			)
			(polygon
				(pts
					(xy 350.0374 -146.177) (xy 350.5454 -146.177) (xy 350.5454 -146.558) (xy 350.0374 -146.558)
				)
			)
		)
	)
	(footprint ""
		(layer "B.Cu")
		(at 351.028 -28.575 180)
		(property "Reference" "C3T8"
			(at 0 0 0)
			(layer "B.SilkS")
			(hide yes)
			(effects
				(font
					(size 1.27 1.27)
				)
				(justify mirror)
			)
		)
		(property "Value" ""
			(at 0 0 0)
			(layer "B.Fab")
			(effects
				(font
					(size 1.27 1.27)
				)
				(justify mirror)
			)
		)
		(duplicate_pad_numbers_are_jumpers no)
		(fp_poly
			(pts
				(xy 0.7239 -0.2159) (xy -0.7239 -0.2159) (xy -0.7239 1.9939) (xy 0.7239 1.9939)
			)
			(stroke
				(width 0)
				(type default)
			)
			(fill no)
			(layer "B.CrtYd")
		)
		(fp_line
			(start 0.7239 1.9939)
			(end -0.7239 1.9939)
			(stroke
				(width 0.1)
				(type default)
			)
			(layer "B.Fab")
		)
		(fp_line
			(start 0.7239 -0.2159)
			(end 0.7239 1.9939)
			(stroke
				(width 0.1)
				(type default)
			)
			(layer "B.Fab")
		)
		(fp_line
			(start -0.7239 1.9939)
			(end -0.7239 -0.2159)
			(stroke
				(width 0.1)
				(type default)
			)
			(layer "B.Fab")
		)
		(fp_line
			(start -0.7239 -0.2159)
			(end 0.7239 -0.2159)
			(stroke
				(width 0.1)
				(type default)
			)
			(layer "B.Fab")
		)
		(pad "1" smd rect
			(at 0 0)
			(size 1.27 1.016)
			(layers "B.Cu" "B.Mask" "B.Paste")
			(net "VR_FET_SW_P12V_STBY_PVPP_ABC")
		)
		(pad "2" smd rect
			(at 0 1.778)
			(size 1.27 1.016)
			(layers "B.Cu" "B.Mask" "B.Paste")
			(net "GND")
		)
		(zone
			(layer "B.Cu")
			(hatch none 0.5)
			(connect_pads
				(clearance 0)
			)
			(min_thickness 0.25)
			(keepout
				(tracks not_allowed)
				(vias allowed)
				(pads allowed)
				(copperpour not_allowed)
				(footprints allowed)
			)
			(placement
				(enabled no)
				(sheetname "")
			)
			(fill
				(thermal_gap 0.5)
				(thermal_bridge_width 0.5)
				(island_removal_mode 0)
			)
			(polygon
				(pts
					(xy 350.393 -29.083) (xy 351.663 -29.083) (xy 351.663 -29.845) (xy 350.393 -29.845)
				)
			)
		)
	)
	(footprint ""
		(layer "B.Cu")
		(at 183.625998 -5.321808)
		(property "Reference" "R6U4"
			(at 0 0 0)
			(layer "B.SilkS")
			(hide yes)
			(effects
				(font
					(size 1.27 1.27)
				)
				(justify mirror)
			)
		)
		(property "Value" ""
			(at 0 0 0)
			(layer "B.Fab")
			(effects
				(font
					(size 1.27 1.27)
				)
				(justify mirror)
			)
		)
		(duplicate_pad_numbers_are_jumpers no)
		(fp_rect
			(start -0.2794 0.9906)
			(end 0.2794 -0.1016)
			(stroke
				(width 0)
				(type default)
			)
			(fill no)
			(layer "B.CrtYd")
		)
		(fp_line
			(start -0.2794 -0.1016)
			(end 0.2794 -0.1016)
			(stroke
				(width 0.1)
				(type default)
			)
			(layer "B.Fab")
		)
		(fp_line
			(start -0.2794 0.9906)
			(end -0.2794 -0.1016)
			(stroke
				(width 0.1)
				(type default)
			)
			(layer "B.Fab")
		)
		(fp_line
			(start 0.2794 -0.1016)
			(end 0.2794 0.9906)
			(stroke
				(width 0.1)
				(type default)
			)
			(layer "B.Fab")
		)
		(fp_line
			(start 0.2794 0.9906)
			(end -0.2794 0.9906)
			(stroke
				(width 0.1)
				(type default)
			)
			(layer "B.Fab")
		)
		(pad "1" smd rect
			(at 0 0 180)
			(size 0.508 0.508)
			(layers "B.Cu" "B.Mask" "B.Paste")
			(net "P3V3")
		)
		(pad "2" smd rect
			(at 0 0.889 180)
			(size 0.508 0.508)
			(layers "B.Cu" "B.Mask" "B.Paste")
			(net "VR_PVTT_ABC_BIAS")
		)
		(zone
			(layer "B.Cu")
			(hatch none 0.5)
			(connect_pads
				(clearance 0)
			)
			(min_thickness 0.25)
			(keepout
				(tracks allowed)
				(vias not_allowed)
				(pads allowed)
				(copperpour not_allowed)
				(footprints allowed)
			)
			(placement
				(enabled no)
				(sheetname "")
			)
			(fill
				(thermal_gap 0.5)
				(thermal_bridge_width 0.5)
				(island_removal_mode 0)
			)
			(polygon
				(pts
					(xy 183.371998 -4.686808) (xy 183.879998 -4.686808) (xy 183.879998 -5.067808) (xy 183.371998 -5.067808)
				)
			)
		)
	)
	(footprint ""
		(layer "B.Cu")
		(at 264.035286 -77.82814)
		(property "Reference" "C5P24"
			(at 0 0 0)
			(layer "B.SilkS")
			(hide yes)
			(effects
				(font
					(size 1.27 1.27)
				)
				(justify mirror)
			)
		)
		(property "Value" ""
			(at 0 0 0)
			(layer "B.Fab")
			(effects
				(font
					(size 1.27 1.27)
				)
				(justify mirror)
			)
		)
		(duplicate_pad_numbers_are_jumpers no)
		(fp_poly
			(pts
				(xy 0.7239 -0.2159) (xy -0.7239 -0.2159) (xy -0.7239 1.9939) (xy 0.7239 1.9939)
			)
			(stroke
				(width 0)
				(type default)
			)
			(fill no)
			(layer "B.CrtYd")
		)
		(fp_line
			(start -0.7239 -0.2159)
			(end 0.7239 -0.2159)
			(stroke
				(width 0.1)
				(type default)
			)
			(layer "B.Fab")
		)
		(fp_line
			(start -0.7239 1.9939)
			(end -0.7239 -0.2159)
			(stroke
				(width 0.1)
				(type default)
			)
			(layer "B.Fab")
		)
		(fp_line
			(start 0.7239 -0.2159)
			(end 0.7239 1.9939)
			(stroke
				(width 0.1)
				(type default)
			)
			(layer "B.Fab")
		)
		(fp_line
			(start 0.7239 1.9939)
			(end -0.7239 1.9939)
			(stroke
				(width 0.1)
				(type default)
			)
			(layer "B.Fab")
		)
		(pad "1" smd rect
			(at 0 0 180)
			(size 1.27 1.016)
			(layers "B.Cu" "B.Mask" "B.Paste")
			(net "PVCCIN_CPU0")
		)
		(pad "2" smd rect
			(at 0 1.778 180)
			(size 1.27 1.016)
			(layers "B.Cu" "B.Mask" "B.Paste")
			(net "GND")
		)
		(zone
			(layer "B.Cu")
			(hatch none 0.5)
			(connect_pads
				(clearance 0)
			)
			(min_thickness 0.25)
			(keepout
				(tracks not_allowed)
				(vias allowed)
				(pads allowed)
				(copperpour not_allowed)
				(footprints allowed)
			)
			(placement
				(enabled no)
				(sheetname "")
			)
			(fill
				(thermal_gap 0.5)
				(thermal_bridge_width 0.5)
				(island_removal_mode 0)
			)
			(polygon
				(pts
					(xy 264.670286 -77.32014) (xy 263.400286 -77.32014) (xy 263.400286 -76.55814) (xy 264.670286 -76.55814)
				)
			)
		)
	)
	(footprint ""
		(layer "B.Cu")
		(at 437.690006 -41.648126 180)
		(property "Reference" "R25W13"
			(at 0 0 0)
			(layer "B.SilkS")
			(hide yes)
			(effects
				(font
					(size 1.27 1.27)
				)
				(justify mirror)
			)
		)
		(property "Value" "*"
			(at -0.064008 -4.108196 180)
			(unlocked yes)
			(layer "B.Fab")
			(hide yes)
			(effects
				(font
					(size 1.27 1.016)
					(thickness 0.1524)
				)
				(justify mirror)
			)
		)
		(property "Device Type" "120R2F-GP_RCL_GP-120R2F-GP,64.A"
			(at -0.064008 -5.632196 180)
			(unlocked yes)
			(layer "B.Fab")
			(hide yes)
			(effects
				(font
					(size 1.27 1.016)
					(thickness 0.1524)
				)
				(justify mirror)
			)
		)
		(duplicate_pad_numbers_are_jumpers no)
		(fp_line
			(start 0.508 -0.9398)
			(end 0.508 0.9398)
			(stroke
				(width 0.1524)
				(type default)
			)
			(layer "B.SilkS")
		)
		(fp_line
			(start -0.508 -0.9398)
			(end 0.508 -0.9398)
			(stroke
				(width 0.1524)
				(type default)
			)
			(layer "B.SilkS")
		)
		(fp_rect
			(start 0.508 0.9398)
			(end -0.508 -0.9398)
			(stroke
				(width 0)
				(type default)
			)
			(fill no)
			(layer "B.CrtYd")
		)
		(fp_rect
			(start 0.508 0.9398)
			(end -0.508 -0.9398)
			(stroke
				(width 0)
				(type default)
			)
			(fill no)
			(layer "B.Fab")
		)
		(pad "1" smd custom
			(at 0 -0.4445)
			(size 0.1397 0.1397)
			(layers "B.Cu" "B.Mask" "B.Paste")
			(net "GND")
			(options
				(clearance outline)
				(anchor circle)
			)
			(primitives
				(gr_poly
					(pts
						(arc
							(start -0.1778 0.2794)
							(mid -0.249642 0.249642)
							(end -0.2794 0.1778)
						)
						(arc
							(start -0.2794 -0.1778)
							(mid -0.249642 -0.249642)
							(end -0.1778 -0.2794)
						)
						(arc
							(start 0.1778 -0.2794)
							(mid 0.249642 -0.249642)
							(end 0.2794 -0.1778)
						)
						(arc
							(start 0.2794 0.1778)
							(mid 0.249642 0.249642)
							(end 0.1778 0.2794)
						)
					)
					(width 0)
					(fill yes)
				)
			)
		)
		(pad "2" smd custom
			(at 0 0.4445)
			(size 0.1397 0.1397)
			(layers "B.Cu" "B.Mask" "B.Paste")
			(net "BMC_M_A1")
			(options
				(clearance outline)
				(anchor circle)
			)
			(primitives
				(gr_poly
					(pts
						(arc
							(start -0.1778 0.2794)
							(mid -0.249642 0.249642)
							(end -0.2794 0.1778)
						)
						(arc
							(start -0.2794 -0.1778)
							(mid -0.249642 -0.249642)
							(end -0.1778 -0.2794)
						)
						(arc
							(start 0.1778 -0.2794)
							(mid 0.249642 -0.249642)
							(end 0.2794 -0.1778)
						)
						(arc
							(start 0.2794 0.1778)
							(mid 0.249642 0.249642)
							(end 0.1778 0.2794)
						)
					)
					(width 0)
					(fill yes)
				)
			)
		)
	)
)
